# S9S_MB_2U (Grand Teton) — schematic netlist excerpt (pin names and nets, part order shuffled) for the footprints in the layout excerpt that follows; sources: Cadence DE-HDL packaged netlist, KiCad conversion of 03242023_DA0F0TMBIJ0_F0T_Motherboard_J_brd_V01_OCP.brd

R3381  Q_RES  1K 1% EMPTY  pkg 0402LF  page 167 : A = FM_P2E_BUF2_RXDET ; B = GND
C913  Q_CAP_DIFFBUS  DIFF BUS_0.22UF 6.3V 20% X6S  pkg C0201  page 173 : \1\ = P5E_CPU0_PE0_TX_C_DP<10> ; \2\ = P5E_CPU0_PE0_TX_DP<10>
R4401  Q_RES  100 1% CHIP  pkg 0402LF  page 122 : A = PVNN_TERM_CPU0 ; B = H_CPU0_MEMHOT_OUT_LVC1_R_N

(kicad_pcb
	(version 20260206)
	(generator "pcbnew")
	(generator_version "10.0")
	(general
		(thickness 1.6)
		(legacy_teardrops no)
	)
	(paper "A4")
	(title_block
		(title "03242023_DA0F0TMBIJ0_F0T_Motherboard_J_brd_V01_OCP.brd")
		(comment 1 "Grand Teton / footprints 2037-2039 of 6105")
	)
	(layers
		(0 "F.Cu" signal "TOP")
		(4 "In1.Cu" signal "GND")
		(6 "In2.Cu" signal "IN1")
		(8 "In3.Cu" signal "GND1")
		(10 "In4.Cu" signal "IN2")
		(12 "In5.Cu" signal "GND2")
		(14 "In6.Cu" signal "IN3")
		(16 "In7.Cu" signal "GND3")
		(18 "In8.Cu" signal "VCC")
		(20 "In9.Cu" signal "VCC1")
		(22 "In10.Cu" signal "GND4")
		(24 "In11.Cu" signal "IN4")
		(26 "In12.Cu" signal "GND5")
		(28 "In13.Cu" signal "IN5")
		(30 "In14.Cu" signal "GND6")
		(32 "In15.Cu" signal "IN6")
		(34 "In16.Cu" signal "GND7")
		(2 "B.Cu" signal "BOTTOM")
		(9 "F.Adhes" user "F.Adhesive")
		(11 "B.Adhes" user "B.Adhesive")
		(13 "F.Paste" user "Package Geometry/Pastemask Top")
		(15 "B.Paste" user "Package Geometry/Pastemask Bottom")
		(5 "F.SilkS" user "Ref Des/Silkscreen Top")
		(7 "B.SilkS" user "Ref Des/Silkscreen Bottom")
		(1 "F.Mask" user "Board Geometry/Soldermask Top")
		(3 "B.Mask" user "Board Geometry/Soldermask Bottom")
		(17 "Dwgs.User" user "User.Drawings")
		(19 "Cmts.User" user "User.Comments")
		(21 "Eco1.User" user "User.Eco1")
		(23 "Eco2.User" user "User.Eco2")
		(25 "Edge.Cuts" user "Board Geometry/Outline")
		(27 "Margin" user)
		(31 "F.CrtYd" user "Package Geometry/Place Bound Top")
		(29 "B.CrtYd" user "Package Geometry/Place Bound Bottom")
		(35 "F.Fab" user "Ref Des/Assembly Top")
		(33 "B.Fab" user "Ref Des/Assembly Bottom")
	)
	(footprint ""
		(layer "F.Cu")
		(at 321.531488 -408.517344 -90)
		(property "Reference" "C913"
			(at 0 0 270)
			(layer "F.SilkS")
			(hide yes)
			(effects
				(font
					(size 1.27 1.27)
				)
			)
		)
		(property "Value" ""
			(at 0 0 270)
			(layer "F.Fab")
			(effects
				(font
					(size 1.27 1.27)
				)
			)
		)
		(duplicate_pad_numbers_are_jumpers no)
		(fp_line
			(start -0.299974 0.150114)
			(end -0.299974 -0.150114)
			(stroke
				(width 0.1)
				(type default)
			)
			(layer "F.Fab")
		)
		(fp_line
			(start 0.299974 0.150114)
			(end -0.299974 0.150114)
			(stroke
				(width 0.1)
				(type default)
			)
			(layer "F.Fab")
		)
		(fp_line
			(start -0.299974 -0.150114)
			(end 0.299974 -0.150114)
			(stroke
				(width 0.1)
				(type default)
			)
			(layer "F.Fab")
		)
		(fp_line
			(start 0.299974 -0.150114)
			(end 0.299974 0.150114)
			(stroke
				(width 0.1)
				(type default)
			)
			(layer "F.Fab")
		)
		(pad "1" smd rect
			(at -0.2667 0 270)
			(size 0.3048 0.381)
			(layers "F.Cu" "F.Mask" "F.Paste")
			(net "P5E_CPU0_PE0_TX_C_DP<10>")
		)
		(pad "2" smd rect
			(at 0.2667 0 270)
			(size 0.3048 0.381)
			(layers "F.Cu" "F.Mask" "F.Paste")
			(net "P5E_CPU0_PE0_TX_DP<10>")
		)
	)
	(footprint ""
		(layer "F.Cu")
		(at 128.70688 -92.674948 -90)
		(property "Reference" "R4401"
			(at 0 0 270)
			(layer "F.SilkS")
			(hide yes)
			(effects
				(font
					(size 1.27 1.27)
				)
			)
		)
		(property "Value" ""
			(at 0 0 270)
			(layer "F.Fab")
			(effects
				(font
					(size 1.27 1.27)
				)
			)
		)
		(duplicate_pad_numbers_are_jumpers no)
		(fp_line
			(start -0.7874 0.4064)
			(end -0.7874 -0.4064)
			(stroke
				(width 0.1524)
				(type default)
			)
			(layer "F.SilkS")
		)
		(fp_line
			(start 0.7874 0.4064)
			(end -0.7874 0.4064)
			(stroke
				(width 0.1524)
				(type default)
			)
			(layer "F.SilkS")
		)
		(fp_line
			(start -0.7874 -0.4064)
			(end 0.7874 -0.4064)
			(stroke
				(width 0.1524)
				(type default)
			)
			(layer "F.SilkS")
		)
		(fp_line
			(start 0.7874 -0.4064)
			(end 0.7874 0.4064)
			(stroke
				(width 0.1524)
				(type default)
			)
			(layer "F.SilkS")
		)
		(fp_line
			(start -0.67945 0.3048)
			(end -0.67945 -0.305054)
			(stroke
				(width 0.1)
				(type default)
			)
			(layer "F.Fab")
		)
		(fp_line
			(start -0.12065 0.3048)
			(end -0.67945 0.3048)
			(stroke
				(width 0.1)
				(type default)
			)
			(layer "F.Fab")
		)
		(fp_line
			(start 0.120396 0.3048)
			(end 0.120396 0.2794)
			(stroke
				(width 0.1)
				(type default)
			)
			(layer "F.Fab")
		)
		(fp_line
			(start 0.67945 0.3048)
			(end 0.120396 0.3048)
			(stroke
				(width 0.1)
				(type default)
			)
			(layer "F.Fab")
		)
		(fp_line
			(start -0.12065 0.2794)
			(end -0.12065 0.3048)
			(stroke
				(width 0.1)
				(type default)
			)
			(layer "F.Fab")
		)
		(fp_line
			(start 0.120396 0.2794)
			(end -0.12065 0.2794)
			(stroke
				(width 0.1)
				(type default)
			)
			(layer "F.Fab")
		)
		(fp_line
			(start -0.12065 -0.2794)
			(end 0.12065 -0.2794)
			(stroke
				(width 0.1)
				(type default)
			)
			(layer "F.Fab")
		)
		(fp_line
			(start 0.12065 -0.2794)
			(end 0.12065 -0.3048)
			(stroke
				(width 0.1)
				(type default)
			)
			(layer "F.Fab")
		)
		(fp_line
			(start 0.12065 -0.3048)
			(end 0.67945 -0.3048)
			(stroke
				(width 0.1)
				(type default)
			)
			(layer "F.Fab")
		)
		(fp_line
			(start 0.67945 -0.3048)
			(end 0.67945 0.3048)
			(stroke
				(width 0.1)
				(type default)
			)
			(layer "F.Fab")
		)
		(fp_line
			(start -0.67945 -0.305054)
			(end -0.12065 -0.305054)
			(stroke
				(width 0.1)
				(type default)
			)
			(layer "F.Fab")
		)
		(fp_line
			(start -0.12065 -0.305054)
			(end -0.12065 -0.2794)
			(stroke
				(width 0.1)
				(type default)
			)
			(layer "F.Fab")
		)
		(pad "1" smd circle
			(at -0.40005 0 270)
			(size 0 0)
			(layers "F.Cu" "F.Mask" "F.Paste")
			(net "PVNN_TERM_CPU0")
		)
		(pad "2" smd circle
			(at 0.40005 0 270)
			(size 0 0)
			(layers "F.Cu" "F.Mask" "F.Paste")
			(net "H_CPU0_MEMHOT_OUT_LVC1_R_N")
		)
	)
	(footprint ""
		(layer "F.Cu")
		(at 33.410398 -390.10717 180)
		(property "Reference" "R3381"
			(at 0 0 180)
			(layer "F.SilkS")
			(hide yes)
			(effects
				(font
					(size 1.27 1.27)
				)
			)
		)
		(property "Value" ""
			(at 0 0 180)
			(layer "F.Fab")
			(effects
				(font
					(size 1.27 1.27)
				)
			)
		)
		(duplicate_pad_numbers_are_jumpers no)
		(fp_line
			(start 0.7874 0.4064)
			(end -0.7874 0.4064)
			(stroke
				(width 0.1524)
				(type default)
			)
			(layer "F.SilkS")
		)
		(fp_line
			(start 0.7874 -0.4064)
			(end 0.7874 0.4064)
			(stroke
				(width 0.1524)
				(type default)
			)
			(layer "F.SilkS")
		)
		(fp_line
			(start -0.7874 0.4064)
			(end -0.7874 -0.4064)
			(stroke
				(width 0.1524)
				(type default)
			)
			(layer "F.SilkS")
		)
		(fp_line
			(start -0.7874 -0.4064)
			(end 0.7874 -0.4064)
			(stroke
				(width 0.1524)
				(type default)
			)
			(layer "F.SilkS")
		)
		(fp_line
			(start 0.67945 0.3048)
			(end 0.120396 0.3048)
			(stroke
				(width 0.1)
				(type default)
			)
			(layer "F.Fab")
		)
		(fp_line
			(start 0.67945 -0.3048)
			(end 0.67945 0.3048)
			(stroke
				(width 0.1)
				(type default)
			)
			(layer "F.Fab")
		)
		(fp_line
			(start 0.12065 -0.2794)
			(end 0.12065 -0.3048)
			(stroke
				(width 0.1)
				(type default)
			)
			(layer "F.Fab")
		)
		(fp_line
			(start 0.12065 -0.3048)
			(end 0.67945 -0.3048)
			(stroke
				(width 0.1)
				(type default)
			)
			(layer "F.Fab")
		)
		(fp_line
			(start 0.120396 0.3048)
			(end 0.120396 0.2794)
			(stroke
				(width 0.1)
				(type default)
			)
			(layer "F.Fab")
		)
		(fp_line
			(start 0.120396 0.2794)
			(end -0.12065 0.2794)
			(stroke
				(width 0.1)
				(type default)
			)
			(layer "F.Fab")
		)
		(fp_line
			(start -0.12065 0.3048)
			(end -0.67945 0.3048)
			(stroke
				(width 0.1)
				(type default)
			)
			(layer "F.Fab")
		)
		(fp_line
			(start -0.12065 0.2794)
			(end -0.12065 0.3048)
			(stroke
				(width 0.1)
				(type default)
			)
			(layer "F.Fab")
		)
		(fp_line
			(start -0.12065 -0.2794)
			(end 0.12065 -0.2794)
			(stroke
				(width 0.1)
				(type default)
			)
			(layer "F.Fab")
		)
		(fp_line
			(start -0.12065 -0.305054)
			(end -0.12065 -0.2794)
			(stroke
				(width 0.1)
				(type default)
			)
			(layer "F.Fab")
		)
		(fp_line
			(start -0.67945 0.3048)
			(end -0.67945 -0.305054)
			(stroke
				(width 0.1)
				(type default)
			)
			(layer "F.Fab")
		)
		(fp_line
			(start -0.67945 -0.305054)
			(end -0.12065 -0.305054)
			(stroke
				(width 0.1)
				(type default)
			)
			(layer "F.Fab")
		)
		(pad "1" smd circle
			(at -0.40005 0 180)
			(size 0 0)
			(layers "F.Cu" "F.Mask" "F.Paste")
			(net "FM_P2E_BUF2_RXDET")
		)
		(pad "2" smd circle
			(at 0.40005 0 180)
			(size 0 0)
			(layers "F.Cu" "F.Mask" "F.Paste")
			(net "GND")
		)
	)
)
